(kicad_pcb
	(version 20221018)
	(generator pcbnew)
	(general
    (thickness 1.7403)
  )
	(paper "A4")
	(title_block
    (title "Data Center RDIMM DDR4 Tester")
    (date "2024-09-30")
    (rev "1.2.4")
		(comment 9 "footprints 119-128 of 690")
	)
	(layers
    (0 "F.Cu" signal)
    (1 "In1.Cu" power)
    (2 "In2.Cu" signal)
    (3 "In3.Cu" power)
    (4 "In4.Cu" power)
    (5 "In5.Cu" signal)
    (6 "In6.Cu" power)
    (7 "In7.Cu" signal)
    (8 "In8.Cu" power)
    (9 "In9.Cu" signal)
    (10 "In10.Cu" power)
    (31 "B.Cu" signal)
    (32 "B.Adhes" user "B.Adhesive")
    (33 "F.Adhes" user "F.Adhesive")
    (34 "B.Paste" user)
    (35 "F.Paste" user)
    (36 "B.SilkS" user "B.Silkscreen")
    (37 "F.SilkS" user "F.Silkscreen")
    (38 "B.Mask" user)
    (39 "F.Mask" user)
    (40 "Dwgs.User" user "User.Drawings")
    (41 "Cmts.User" user "User.Comments")
    (42 "Eco1.User" user "User.Eco1")
    (43 "Eco2.User" user "User.Eco2")
    (44 "Edge.Cuts" user)
    (45 "Margin" user)
    (46 "B.CrtYd" user "B.Courtyard")
    (47 "F.CrtYd" user "F.Courtyard")
    (48 "B.Fab" user)
    (49 "F.Fab" user)
  )
	(footprint "data-center-rdimm-ddr4-tester-footprints:R_0402_1005Metric" (layer "F.Cu")
    (at 211.165 115.35 -90)
    (descr "Resistor SMD 0402")
    (tags "resistor SMD 0402")
    (property "Author" "Antmicro")
    (property "Current" "1A")
    (property "License" "Apache-2.0")
    (property "MPN" "ERJ2GE0R00X")
    (property "Manufacturer" "Panasonic")
    (property "Sheetfile" "interfaces.kicad_sch")
    (property "Sheetname" "Interfaces")
    (property "Tolerance" "")
    (property "Val" "0R")
    (property "ki_description" "0R resistor in 0402 package with unspecified tolerance")
    (attr smd)
    (fp_text reference "R142" (at -3.105 -0.35 -90) (layer "F.SilkS")
        (effects (font (size 0.7 0.7) (thickness 0.15)) (justify left bottom))
    )
    (fp_text value "R_0R_0402" (at 0 1.4 -90) (layer "F.Fab") hide
        (effects (font (size 0.7 0.7) (thickness 0.15)) (justify left bottom))
    )
    (fp_text user "License: Apache-2.0" (at -0.95 5.169 -90) (layer "F.Fab") hide
        (effects (font (size 0.7 0.7) (thickness 0.15)) (justify left bottom))
    )
    (fp_text user "${REFERENCE}" (at -0.95 3.168 -90) (layer "F.Fab") hide
        (effects (font (size 0.7 0.7) (thickness 0.15)) (justify left bottom))
    )
    (fp_text user "Author: Antmicro" (at -0.95 4.169 -90) (layer "F.Fab") hide
        (effects (font (size 0.7 0.7) (thickness 0.15)) (justify left bottom))
    )
    (fp_rect (start -0.93 -0.47) (end 0.93 0.47)
      (stroke (width 0.05) (type solid)) (fill none) (layer "F.CrtYd"))
    (fp_rect (start -0.5 -0.25) (end 0.5 0.25)
      (stroke (width 0.15) (type solid)) (fill none) (layer "F.Fab"))
    (pad "1" smd roundrect (at -0.485 0 270) (size 0.59 0.64) (layers "F.Cu" "F.Paste" "F.Mask") (roundrect_rratio 0.25)
      (net 57 "TMDS_D0_P") (pintype "passive"))
    (pad "2" smd roundrect (at 0.485 0 270) (size 0.59 0.64) (layers "F.Cu" "F.Paste" "F.Mask") (roundrect_rratio 0.25)
      (net 45 "C_TMDS_D0_P") (pintype "passive"))
  )
	(footprint "data-center-rdimm-ddr4-tester-footprints:R_0402_1005Metric" (layer "F.Cu")
    (at 211.64 113.135 -90)
    (descr "Resistor SMD 0402")
    (tags "resistor SMD 0402")
    (property "Author" "Antmicro")
    (property "Current" "1A")
    (property "License" "Apache-2.0")
    (property "MPN" "ERJ2GE0R00X")
    (property "Manufacturer" "Panasonic")
    (property "Sheetfile" "interfaces.kicad_sch")
    (property "Sheetname" "Interfaces")
    (property "Tolerance" "")
    (property "Val" "0R")
    (property "ki_description" "0R resistor in 0402 package with unspecified tolerance")
    (attr smd)
    (fp_text reference "R143" (at -3.515 -0.34 -90) (layer "F.SilkS")
        (effects (font (size 0.7 0.7) (thickness 0.15)) (justify left bottom))
    )
    (fp_text value "R_0R_0402" (at 0 1.4 -90) (layer "F.Fab") hide
        (effects (font (size 0.7 0.7) (thickness 0.15)) (justify left bottom))
    )
    (fp_text user "Author: Antmicro" (at -0.95 4.169 -90) (layer "F.Fab") hide
        (effects (font (size 0.7 0.7) (thickness 0.15)) (justify left bottom))
    )
    (fp_text user "${REFERENCE}" (at -0.95 3.168 -90) (layer "F.Fab") hide
        (effects (font (size 0.7 0.7) (thickness 0.15)) (justify left bottom))
    )
    (fp_text user "License: Apache-2.0" (at -0.95 5.169 -90) (layer "F.Fab") hide
        (effects (font (size 0.7 0.7) (thickness 0.15)) (justify left bottom))
    )
    (fp_rect (start -0.93 -0.47) (end 0.93 0.47)
      (stroke (width 0.05) (type solid)) (fill none) (layer "F.CrtYd"))
    (fp_rect (start -0.5 -0.25) (end 0.5 0.25)
      (stroke (width 0.15) (type solid)) (fill none) (layer "F.Fab"))
    (pad "1" smd roundrect (at -0.485 0 270) (size 0.59 0.64) (layers "F.Cu" "F.Paste" "F.Mask") (roundrect_rratio 0.25)
      (net 60 "TMDS_D1_N") (pintype "passive"))
    (pad "2" smd roundrect (at 0.485 0 270) (size 0.59 0.64) (layers "F.Cu" "F.Paste" "F.Mask") (roundrect_rratio 0.25)
      (net 54 "C_TMDS_D1_N") (pintype "passive"))
  )
	(footprint "data-center-rdimm-ddr4-tester-footprints:R_0402_1005Metric" (layer "F.Cu")
    (at 212.65 113.135 -90)
    (descr "Resistor SMD 0402")
    (tags "resistor SMD 0402")
    (property "Author" "Antmicro")
    (property "Current" "1A")
    (property "License" "Apache-2.0")
    (property "MPN" "ERJ2GE0R00X")
    (property "Manufacturer" "Panasonic")
    (property "Sheetfile" "interfaces.kicad_sch")
    (property "Sheetname" "Interfaces")
    (property "Tolerance" "")
    (property "Val" "0R")
    (property "ki_description" "0R resistor in 0402 package with unspecified tolerance")
    (attr smd)
    (fp_text reference "R144" (at -3.515 -0.34 -90) (layer "F.SilkS")
        (effects (font (size 0.7 0.7) (thickness 0.15)) (justify left bottom))
    )
    (fp_text value "R_0R_0402" (at 0 1.4 -90) (layer "F.Fab") hide
        (effects (font (size 0.7 0.7) (thickness 0.15)) (justify left bottom))
    )
    (fp_text user "${REFERENCE}" (at -0.95 3.168 -90) (layer "F.Fab") hide
        (effects (font (size 0.7 0.7) (thickness 0.15)) (justify left bottom))
    )
    (fp_text user "License: Apache-2.0" (at -0.95 5.169 -90) (layer "F.Fab") hide
        (effects (font (size 0.7 0.7) (thickness 0.15)) (justify left bottom))
    )
    (fp_text user "Author: Antmicro" (at -0.95 4.169 -90) (layer "F.Fab") hide
        (effects (font (size 0.7 0.7) (thickness 0.15)) (justify left bottom))
    )
    (fp_rect (start -0.93 -0.47) (end 0.93 0.47)
      (stroke (width 0.05) (type solid)) (fill none) (layer "F.CrtYd"))
    (fp_rect (start -0.5 -0.25) (end 0.5 0.25)
      (stroke (width 0.15) (type solid)) (fill none) (layer "F.Fab"))
    (pad "1" smd roundrect (at -0.485 0 270) (size 0.59 0.64) (layers "F.Cu" "F.Paste" "F.Mask") (roundrect_rratio 0.25)
      (net 59 "TMDS_D1_P") (pintype "passive"))
    (pad "2" smd roundrect (at 0.485 0 270) (size 0.59 0.64) (layers "F.Cu" "F.Paste" "F.Mask") (roundrect_rratio 0.25)
      (net 46 "C_TMDS_D1_P") (pintype "passive"))
  )
	(footprint "data-center-rdimm-ddr4-tester-footprints:R_0402_1005Metric" (layer "F.Cu")
    (at 213.14 115.35 -90)
    (descr "Resistor SMD 0402")
    (tags "resistor SMD 0402")
    (property "Author" "Antmicro")
    (property "Current" "1A")
    (property "License" "Apache-2.0")
    (property "MPN" "ERJ2GE0R00X")
    (property "Manufacturer" "Panasonic")
    (property "Sheetfile" "interfaces.kicad_sch")
    (property "Sheetname" "Interfaces")
    (property "Tolerance" "")
    (property "Val" "0R")
    (property "ki_description" "0R resistor in 0402 package with unspecified tolerance")
    (attr smd)
    (fp_text reference "R145" (at -3.105 -0.35 -90) (layer "F.SilkS")
        (effects (font (size 0.7 0.7) (thickness 0.15)) (justify left bottom))
    )
    (fp_text value "R_0R_0402" (at 0 1.4 -90) (layer "F.Fab") hide
        (effects (font (size 0.7 0.7) (thickness 0.15)) (justify left bottom))
    )
    (fp_text user "${REFERENCE}" (at -0.95 3.168 -90) (layer "F.Fab") hide
        (effects (font (size 0.7 0.7) (thickness 0.15)) (justify left bottom))
    )
    (fp_text user "License: Apache-2.0" (at -0.95 5.169 -90) (layer "F.Fab") hide
        (effects (font (size 0.7 0.7) (thickness 0.15)) (justify left bottom))
    )
    (fp_text user "Author: Antmicro" (at -0.95 4.169 -90) (layer "F.Fab") hide
        (effects (font (size 0.7 0.7) (thickness 0.15)) (justify left bottom))
    )
    (fp_rect (start -0.93 -0.47) (end 0.93 0.47)
      (stroke (width 0.05) (type solid)) (fill none) (layer "F.CrtYd"))
    (fp_rect (start -0.5 -0.25) (end 0.5 0.25)
      (stroke (width 0.15) (type solid)) (fill none) (layer "F.Fab"))
    (pad "1" smd roundrect (at -0.485 0 270) (size 0.59 0.64) (layers "F.Cu" "F.Paste" "F.Mask") (roundrect_rratio 0.25)
      (net 62 "TMDS_D2_N") (pintype "passive"))
    (pad "2" smd roundrect (at 0.485 0 270) (size 0.59 0.64) (layers "F.Cu" "F.Paste" "F.Mask") (roundrect_rratio 0.25)
      (net 47 "C_TMDS_D2_N") (pintype "passive"))
  )
	(footprint "data-center-rdimm-ddr4-tester-footprints:R_0402_1005Metric" (layer "F.Cu")
    (at 214.156 115.35 -90)
    (descr "Resistor SMD 0402")
    (tags "resistor SMD 0402")
    (property "Author" "Antmicro")
    (property "Current" "1A")
    (property "License" "Apache-2.0")
    (property "MPN" "ERJ2GE0R00X")
    (property "Manufacturer" "Panasonic")
    (property "Sheetfile" "interfaces.kicad_sch")
    (property "Sheetname" "Interfaces")
    (property "Tolerance" "")
    (property "Val" "0R")
    (property "ki_description" "0R resistor in 0402 package with unspecified tolerance")
    (attr smd)
    (fp_text reference "R146" (at -3.105 -0.35 -90) (layer "F.SilkS")
        (effects (font (size 0.7 0.7) (thickness 0.15)) (justify left bottom))
    )
    (fp_text value "R_0R_0402" (at 0 1.4 -90) (layer "F.Fab") hide
        (effects (font (size 0.7 0.7) (thickness 0.15)) (justify left bottom))
    )
    (fp_text user "Author: Antmicro" (at -0.95 4.169 -90) (layer "F.Fab") hide
        (effects (font (size 0.7 0.7) (thickness 0.15)) (justify left bottom))
    )
    (fp_text user "${REFERENCE}" (at -0.95 3.168 -90) (layer "F.Fab") hide
        (effects (font (size 0.7 0.7) (thickness 0.15)) (justify left bottom))
    )
    (fp_text user "License: Apache-2.0" (at -0.95 5.169 -90) (layer "F.Fab") hide
        (effects (font (size 0.7 0.7) (thickness 0.15)) (justify left bottom))
    )
    (fp_rect (start -0.93 -0.47) (end 0.93 0.47)
      (stroke (width 0.05) (type solid)) (fill none) (layer "F.CrtYd"))
    (fp_rect (start -0.5 -0.25) (end 0.5 0.25)
      (stroke (width 0.15) (type solid)) (fill none) (layer "F.Fab"))
    (pad "1" smd roundrect (at -0.485 0 270) (size 0.59 0.64) (layers "F.Cu" "F.Paste" "F.Mask") (roundrect_rratio 0.25)
      (net 61 "TMDS_D2_P") (pintype "passive"))
    (pad "2" smd roundrect (at 0.485 0 270) (size 0.59 0.64) (layers "F.Cu" "F.Paste" "F.Mask") (roundrect_rratio 0.25)
      (net 48 "C_TMDS_D2_P") (pintype "passive"))
  )
	(footprint "data-center-rdimm-ddr4-tester-footprints:Testpoint_smd_1mm" locked (layer "F.Cu")
    (at 206.5993 119.16 90)
    (property "Author" "Antmicro")
    (property "License" "Apache-2.0")
    (property "MPN" "")
    (property "Manufacturer" "")
    (property "Sheetfile" "interfaces.kicad_sch")
    (property "Sheetname" "Interfaces")
    (property "ki_description" "Test Point 1mm")
    (attr exclude_from_pos_files)
    (fp_text reference "TP1" (at 0.5 0.3707 90) (layer "F.SilkS")
        (effects (font (size 0.7 0.7) (thickness 0.15)) (justify left bottom))
    )
    (fp_text value "TP_1mm_SMD" (at 0 1.4 90) (layer "F.Fab") hide
        (effects (font (size 0.7 0.7) (thickness 0.15)) (justify left bottom))
    )
    (fp_text user "Author: Antmicro" (at -0.5 4 90) (layer "F.Fab") hide
        (effects (font (size 0.7 0.7) (thickness 0.15)) (justify left bottom))
    )
    (fp_text user "${REFERENCE}" (at -0.5 2.8 90) (layer "F.Fab") hide
        (effects (font (size 0.7 0.7) (thickness 0.15)) (justify left bottom))
    )
    (fp_text user "License: Apache-2.0" (at -0.5 5.2 90) (layer "F.Fab") hide
        (effects (font (size 0.7 0.7) (thickness 0.15)) (justify left bottom))
    )
    (pad "1" smd circle locked (at 0 0 90) (size 1 1) (layers "F.Cu" "F.Mask")
      (net 556 "Net-(J6-CEC)") (pinfunction "1") (pintype "passive"))
  )
	(footprint "data-center-rdimm-ddr4-tester-footprints:Testpoint_smd_1mm" locked (layer "F.Cu")
    (at 206.0725 121.16 90)
    (property "Author" "Antmicro")
    (property "License" "Apache-2.0")
    (property "MPN" "")
    (property "Manufacturer" "")
    (property "Sheetfile" "interfaces.kicad_sch")
    (property "Sheetname" "Interfaces")
    (property "ki_description" "Test Point 1mm")
    (attr exclude_from_pos_files)
    (fp_text reference "TP2" (at -0.97 1.4275 90) (layer "F.SilkS")
        (effects (font (size 0.7 0.7) (thickness 0.15)) (justify left bottom))
    )
    (fp_text value "TP_1mm_SMD" (at 0 1.4 90) (layer "F.Fab") hide
        (effects (font (size 0.7 0.7) (thickness 0.15)) (justify left bottom))
    )
    (fp_text user "License: Apache-2.0" (at -0.5 5.2 90) (layer "F.Fab") hide
        (effects (font (size 0.7 0.7) (thickness 0.15)) (justify left bottom))
    )
    (fp_text user "${REFERENCE}" (at -0.5 2.8 90) (layer "F.Fab") hide
        (effects (font (size 0.7 0.7) (thickness 0.15)) (justify left bottom))
    )
    (fp_text user "Author: Antmicro" (at -0.5 4 90) (layer "F.Fab") hide
        (effects (font (size 0.7 0.7) (thickness 0.15)) (justify left bottom))
    )
    (pad "1" smd circle locked (at 0 0 90) (size 1 1) (layers "F.Cu" "F.Mask")
      (net 560 "Net-(J6-SCL)") (pinfunction "1") (pintype "passive"))
  )
	(footprint "data-center-rdimm-ddr4-tester-footprints:Testpoint_smd_1mm" locked (layer "F.Cu")
    (at 203.1233 119.16 90)
    (property "Author" "Antmicro")
    (property "License" "Apache-2.0")
    (property "MPN" "")
    (property "Manufacturer" "")
    (property "Sheetfile" "interfaces.kicad_sch")
    (property "Sheetname" "Interfaces")
    (property "ki_description" "Test Point 1mm")
    (attr exclude_from_pos_files)
    (fp_text reference "TP3" (at 0.47 0.3467 90) (layer "F.SilkS")
        (effects (font (size 0.7 0.7) (thickness 0.15)) (justify left bottom))
    )
    (fp_text value "TP_1mm_SMD" (at 0 1.4 90) (layer "F.Fab") hide
        (effects (font (size 0.7 0.7) (thickness 0.15)) (justify left bottom))
    )
    (fp_text user "${REFERENCE}" (at -0.5 2.8 90) (layer "F.Fab") hide
        (effects (font (size 0.7 0.7) (thickness 0.15)) (justify left bottom))
    )
    (fp_text user "License: Apache-2.0" (at -0.5 5.2 90) (layer "F.Fab") hide
        (effects (font (size 0.7 0.7) (thickness 0.15)) (justify left bottom))
    )
    (fp_text user "Author: Antmicro" (at -0.5 4 90) (layer "F.Fab") hide
        (effects (font (size 0.7 0.7) (thickness 0.15)) (justify left bottom))
    )
    (pad "1" smd circle locked (at 0 0 90) (size 1 1) (layers "F.Cu" "F.Mask")
      (net 563 "Net-(J6-HPD{slash}HEAC-)") (pinfunction "1") (pintype "passive"))
  )
	(footprint "data-center-rdimm-ddr4-tester-footprints:Testpoint_smd_1mm" locked (layer "F.Cu")
    (at 205.0725 119.16 90)
    (property "Author" "Antmicro")
    (property "License" "Apache-2.0")
    (property "MPN" "")
    (property "Manufacturer" "")
    (property "Sheetfile" "interfaces.kicad_sch")
    (property "Sheetname" "Interfaces")
    (property "ki_description" "Test Point 1mm")
    (attr exclude_from_pos_files)
    (fp_text reference "TP4" (at 0.54 0.3775 90) (layer "F.SilkS")
        (effects (font (size 0.7 0.7) (thickness 0.15)) (justify left bottom))
    )
    (fp_text value "TP_1mm_SMD" (at 0 1.4 90) (layer "F.Fab") hide
        (effects (font (size 0.7 0.7) (thickness 0.15)) (justify left bottom))
    )
    (fp_text user "License: Apache-2.0" (at -0.5 5.2 90) (layer "F.Fab") hide
        (effects (font (size 0.7 0.7) (thickness 0.15)) (justify left bottom))
    )
    (fp_text user "Author: Antmicro" (at -0.5 4 90) (layer "F.Fab") hide
        (effects (font (size 0.7 0.7) (thickness 0.15)) (justify left bottom))
    )
    (fp_text user "${REFERENCE}" (at -0.5 2.8 90) (layer "F.Fab") hide
        (effects (font (size 0.7 0.7) (thickness 0.15)) (justify left bottom))
    )
    (pad "1" smd circle locked (at 0 0 90) (size 1 1) (layers "F.Cu" "F.Mask")
      (net 561 "Net-(J6-SDA)") (pinfunction "1") (pintype "passive"))
  )
	(footprint "data-center-rdimm-ddr4-tester-footprints:Testpoint_smd_1mm" locked (layer "F.Cu")
    (at 204.1233 121.16 90)
    (property "Author" "Antmicro")
    (property "License" "Apache-2.0")
    (property "MPN" "")
    (property "Manufacturer" "")
    (property "Sheetfile" "interfaces.kicad_sch")
    (property "Sheetname" "Interfaces")
    (property "ki_description" "Test Point 1mm")
    (attr exclude_from_pos_files)
    (fp_text reference "TP5" (at -0.9 -0.6933 90) (layer "F.SilkS")
        (effects (font (size 0.7 0.7) (thickness 0.15)) (justify left bottom))
    )
    (fp_text value "TP_1mm_SMD" (at 0 1.4 90) (layer "F.Fab") hide
        (effects (font (size 0.7 0.7) (thickness 0.15)) (justify left bottom))
    )
    (fp_text user "Author: Antmicro" (at -0.5 4 90) (layer "F.Fab") hide
        (effects (font (size 0.7 0.7) (thickness 0.15)) (justify left bottom))
    )
    (fp_text user "License: Apache-2.0" (at -0.5 5.2 90) (layer "F.Fab") hide
        (effects (font (size 0.7 0.7) (thickness 0.15)) (justify left bottom))
    )
    (fp_text user "${REFERENCE}" (at -0.5 2.8 90) (layer "F.Fab") hide
        (effects (font (size 0.7 0.7) (thickness 0.15)) (justify left bottom))
    )
    (pad "1" smd circle locked (at 0 0 90) (size 1 1) (layers "F.Cu" "F.Mask")
      (net 562 "Net-(J6-+5V)") (pinfunction "1") (pintype "passive"))
  )
)
